FILE_TYPE = CONNECTIVITY;
{Allegro Design Entry HDL 17.2-2016 S081 (4005846) 1/11/2022}
"PAGE_NUMBER" = 33;
0"NC";
1"UPI_CPU0_CPU1_P1P0_DP<23:0>";
2"UPI_CPU0_CPU1_P1P0_DN<23:0>";
3"UPI_CPU1_CPU0_P0P1_DP<23:0>";
4"UPI_CPU1_CPU0_P0P1_DN<23:0>";
5"UPI_CPU1_CPU0_P0P1_DP<23>";
6"UPI_CPU1_CPU0_P0P1_DP<22>";
7"UPI_CPU1_CPU0_P0P1_DN<21>";
8"UPI_CPU1_CPU0_P0P1_DP<20>";
9"UPI_CPU1_CPU0_P0P1_DP<19>";
10"UPI_CPU1_CPU0_P0P1_DN<18>";
11"UPI_CPU1_CPU0_P0P1_DP<17>";
12"UPI_CPU1_CPU0_P0P1_DN<16>";
13"UPI_CPU1_CPU0_P0P1_DN<15>";
14"UPI_CPU1_CPU0_P0P1_DN<14>";
15"UPI_CPU1_CPU0_P0P1_DN<13>";
16"UPI_CPU1_CPU0_P0P1_DP<12>";
17"UPI_CPU1_CPU0_P0P1_DN<11>";
18"UPI_CPU1_CPU0_P0P1_DN<10>";
19"UPI_CPU1_CPU0_P0P1_DN<9>";
20"UPI_CPU1_CPU0_P0P1_DN<8>";
21"UPI_CPU1_CPU0_P0P1_DN<7>";
22"UPI_CPU1_CPU0_P0P1_DN<6>";
23"UPI_CPU1_CPU0_P0P1_DN<5>";
24"UPI_CPU1_CPU0_P0P1_DN<4>";
25"UPI_CPU1_CPU0_P0P1_DN<3>";
26"UPI_CPU1_CPU0_P0P1_DP<2>";
27"UPI_CPU1_CPU0_P0P1_DN<1>";
28"UPI_CPU1_CPU0_P0P1_DN<0>";
29"UPI_CPU1_CPU0_P0P1_DN<23>";
30"UPI_CPU1_CPU0_P0P1_DN<22>";
31"UPI_CPU1_CPU0_P0P1_DP<21>";
32"UPI_CPU1_CPU0_P0P1_DN<20>";
33"UPI_CPU1_CPU0_P0P1_DN<19>";
34"UPI_CPU1_CPU0_P0P1_DP<18>";
35"UPI_CPU1_CPU0_P0P1_DN<17>";
36"UPI_CPU1_CPU0_P0P1_DP<16>";
37"UPI_CPU1_CPU0_P0P1_DP<15>";
38"UPI_CPU1_CPU0_P0P1_DP<14>";
39"UPI_CPU1_CPU0_P0P1_DP<13>";
40"UPI_CPU1_CPU0_P0P1_DN<12>";
41"UPI_CPU1_CPU0_P0P1_DP<11>";
42"UPI_CPU1_CPU0_P0P1_DP<10>";
43"UPI_CPU1_CPU0_P0P1_DP<9>";
44"UPI_CPU1_CPU0_P0P1_DP<8>";
45"UPI_CPU1_CPU0_P0P1_DP<7>";
46"UPI_CPU1_CPU0_P0P1_DP<6>";
47"UPI_CPU1_CPU0_P0P1_DP<5>";
48"UPI_CPU1_CPU0_P0P1_DP<4>";
49"UPI_CPU1_CPU0_P0P1_DP<3>";
50"UPI_CPU1_CPU0_P0P1_DN<2>";
51"UPI_CPU1_CPU0_P0P1_DP<1>";
52"UPI_CPU1_CPU0_P0P1_DP<0>";
53"UPI_CPU0_CPU1_P1P0_DP<23>";
54"UPI_CPU0_CPU1_P1P0_DN<22>";
55"UPI_CPU0_CPU1_P1P0_DP<21>";
56"UPI_CPU0_CPU1_P1P0_DP<20>";
57"UPI_CPU0_CPU1_P1P0_DP<19>";
58"UPI_CPU0_CPU1_P1P0_DP<18>";
59"UPI_CPU0_CPU1_P1P0_DP<17>";
60"UPI_CPU0_CPU1_P1P0_DP<16>";
61"UPI_CPU0_CPU1_P1P0_DP<15>";
62"UPI_CPU0_CPU1_P1P0_DP<14>";
63"UPI_CPU0_CPU1_P1P0_DP<13>";
64"UPI_CPU0_CPU1_P1P0_DP<12>";
65"UPI_CPU0_CPU1_P1P0_DP<11>";
66"UPI_CPU0_CPU1_P1P0_DP<10>";
67"UPI_CPU0_CPU1_P1P0_DN<9>";
68"UPI_CPU0_CPU1_P1P0_DN<8>";
69"UPI_CPU0_CPU1_P1P0_DN<7>";
70"UPI_CPU0_CPU1_P1P0_DN<6>";
71"UPI_CPU0_CPU1_P1P0_DP<5>";
72"UPI_CPU0_CPU1_P1P0_DN<4>";
73"UPI_CPU0_CPU1_P1P0_DP<3>";
74"UPI_CPU0_CPU1_P1P0_DN<2>";
75"UPI_CPU0_CPU1_P1P0_DN<1>";
76"UPI_CPU0_CPU1_P1P0_DN<0>";
77"UPI_CPU0_CPU1_P1P0_DN<23>";
78"UPI_CPU0_CPU1_P1P0_DP<22>";
79"UPI_CPU0_CPU1_P1P0_DN<21>";
80"UPI_CPU0_CPU1_P1P0_DN<20>";
81"UPI_CPU0_CPU1_P1P0_DN<19>";
82"UPI_CPU0_CPU1_P1P0_DN<18>"$PNN"UPI_CPU0_CPU1_P1P0_DN<18>";
83"UPI_CPU0_CPU1_P1P0_DN<17>";
84"UPI_CPU0_CPU1_P1P0_DN<16>";
85"UPI_CPU0_CPU1_P1P0_DN<15>";
86"UPI_CPU0_CPU1_P1P0_DN<14>"$PNN"UPI_CPU0_CPU1_P1P0_DN<14>";
87"UPI_CPU0_CPU1_P1P0_DN<13>";
88"UPI_CPU0_CPU1_P1P0_DN<12>";
89"UPI_CPU0_CPU1_P1P0_DN<11>";
90"UPI_CPU0_CPU1_P1P0_DN<10>";
91"UPI_CPU0_CPU1_P1P0_DP<9>";
92"UPI_CPU0_CPU1_P1P0_DP<8>";
93"UPI_CPU0_CPU1_P1P0_DP<7>";
94"UPI_CPU0_CPU1_P1P0_DP<6>";
95"UPI_CPU0_CPU1_P1P0_DN<5>";
96"UPI_CPU0_CPU1_P1P0_DP<4>";
97"UPI_CPU0_CPU1_P1P0_DN<3>";
98"UPI_CPU0_CPU1_P1P0_DP<2>";
99"UPI_CPU0_CPU1_P1P0_DP<1>";
100"UPI_CPU0_CPU1_P1P0_DP<0>";
%"TAP"
"1","(-850,1175)","2","standard","I1";
;
CDS_LIB"standard"
BODY_TYPE"PLUMBING"
HDL_TAP"TRUE";
"B \NAC \NWC"4;
"S \NAC"
BN"0"28;
%"TAP"
"1","(-850,1625)","2","standard","I10";
;
CDS_LIB"standard"
BODY_TYPE"PLUMBING"
HDL_TAP"TRUE";
"B \NAC \NWC"4;
"S \NAC"
BN"9"19;
%"SOCKET4677_AZIF0045P001C01CS"
"23","(1050,2375)","0","pure_quanta","I102";
;
PART_NUMBER"DGA^7000023"
VALUE"SOCKET4677_AZIF0045-P001C01CS"
MATERIAL"IO"
PART_TYPE"SMLF"
$LOCATION"U2"
CDS_LMAN_SYM_OUTLINE"-1050,1350,1050,-1350"
NEEDS_NO_SIZE"TRUE"
CDS_LIB"pure_quanta"
CDS_LOCATION"U2"
$SEC"23"
CDS_SEC"23";
"UPI1_TX_DP0"
$PN"EE5"100;
"UPI1_TX_DP1"
$PN"ED6"99;
"UPI1_TX_DP2"
$PN"EA5"98;
"UPI1_TX_DP3"
$PN"DW7"97;
"UPI1_TX_DP4"
$PN"DU5"96;
"UPI1_TX_DP5"
$PN"DR7"95;
"UPI1_TX_DP6"
$PN"DN5"94;
"UPI1_TX_DP7"
$PN"DM6"93;
"UPI1_TX_DP8"
$PN"DJ5"92;
"UPI1_TX_DP9"
$PN"DG7"91;
"UPI1_TX_DP10"
$PN"DF6"90;
"UPI1_TX_DP11"
$PN"DC7"89;
"UPI1_TX_DP12"
$PN"DB6"88;
"UPI1_TX_DP13"
$PN"CW7"87;
"UPI1_TX_DP14"
$PN"CV6"86;
"UPI1_TX_DP15"
$PN"CR7"85;
"UPI1_TX_DP16"
$PN"CP6"84;
"UPI1_TX_DP17"
$PN"CL7"83;
"UPI1_TX_DP18"
$PN"CK6"82;
"UPI1_TX_DP19"
$PN"CG7"81;
"UPI1_TX_DP20"
$PN"CF6"80;
"UPI1_TX_DP21"
$PN"CC7"79;
"UPI1_TX_DP22"
$PN"CB6"78;
"UPI1_TX_DP23"
$PN"BW7"77;
"UPI1_TX_DN0"
$PN"EF6"76;
"UPI1_TX_DN1"
$PN"EC7"75;
"UPI1_TX_DN2"
$PN"EB6"74;
"UPI1_TX_DN3"
$PN"DY6"73;
"UPI1_TX_DN4"
$PN"DV6"72;
"UPI1_TX_DN5"
$PN"DT6"71;
"UPI1_TX_DN6"
$PN"DP6"70;
"UPI1_TX_DN7"
$PN"DL7"69;
"UPI1_TX_DN8"
$PN"DK6"68;
"UPI1_TX_DN9"
$PN"DH6"67;
"UPI1_TX_DN10"
$PN"DE5"66;
"UPI1_TX_DN11"
$PN"DD6"65;
"UPI1_TX_DN12"
$PN"DA5"64;
"UPI1_TX_DN13"
$PN"CY6"63;
"UPI1_TX_DN14"
$PN"CU5"62;
"UPI1_TX_DN15"
$PN"CT6"61;
"UPI1_TX_DN16"
$PN"CN5"60;
"UPI1_TX_DN17"
$PN"CM6"59;
"UPI1_TX_DN18"
$PN"CJ5"58;
"UPI1_TX_DN19"
$PN"CH6"57;
"UPI1_TX_DN20"
$PN"CE5"56;
"UPI1_TX_DN21"
$PN"CD6"55;
"UPI1_TX_DN22"
$PN"CA5"54;
"UPI1_TX_DN23"
$PN"BY6"53;
"UPI1_RX_DP0"
$PN"EJ3"52;
"UPI1_RX_DP1"
$PN"EG3"51;
"UPI1_RX_DP2"
$PN"EC3"50;
"UPI1_RX_DP3"
$PN"EB2"49;
"UPI1_RX_DP4"
$PN"DW3"48;
"UPI1_RX_DP5"
$PN"DV2"47;
"UPI1_RX_DP6"
$PN"DR3"46;
"UPI1_RX_DP7"
$PN"DP2"45;
"UPI1_RX_DP8"
$PN"DM2"44;
"UPI1_RX_DP9"
$PN"DK2"43;
"UPI1_RX_DP10"
$PN"DH2"42;
"UPI1_RX_DP11"
$PN"DF2"41;
"UPI1_RX_DP12"
$PN"DC3"40;
"UPI1_RX_DP13"
$PN"DA1"39;
"UPI1_RX_DP14"
$PN"CW3"38;
"UPI1_RX_DP15"
$PN"CU1"37;
"UPI1_RX_DP16"
$PN"CT2"36;
"UPI1_RX_DP17"
$PN"CP2"35;
"UPI1_RX_DP18"
$PN"CM2"34;
"UPI1_RX_DP19"
$PN"CK2"33;
"UPI1_RX_DP20"
$PN"CG3"32;
"UPI1_RX_DP21"
$PN"CE1"31;
"UPI1_RX_DP22"
$PN"CC3"30;
"UPI1_RX_DP23"
$PN"BY2"29;
"UPI1_RX_DN0"
$PN"EH2"28;
"UPI1_RX_DN1"
$PN"EE3"27;
"UPI1_RX_DN2"
$PN"ED2"26;
"UPI1_RX_DN3"
$PN"EA1"25;
"UPI1_RX_DN4"
$PN"DY2"24;
"UPI1_RX_DN5"
$PN"DU1"23;
"UPI1_RX_DN6"
$PN"DT2"22;
"UPI1_RX_DN7"
$PN"DN1"21;
"UPI1_RX_DN8"
$PN"DL3"20;
"UPI1_RX_DN9"
$PN"DJ1"19;
"UPI1_RX_DN10"
$PN"DG3"18;
"UPI1_RX_DN11"
$PN"DE1"17;
"UPI1_RX_DN12"
$PN"DD2"16;
"UPI1_RX_DN13"
$PN"DB2"15;
"UPI1_RX_DN14"
$PN"CY2"14;
"UPI1_RX_DN15"
$PN"CV2"13;
"UPI1_RX_DN16"
$PN"CR3"12;
"UPI1_RX_DN17"
$PN"CN1"11;
"UPI1_RX_DN18"
$PN"CL3"10;
"UPI1_RX_DN19"
$PN"CJ1"9;
"UPI1_RX_DN20"
$PN"CH2"8;
"UPI1_RX_DN21"
$PN"CF2"7;
"UPI1_RX_DN22"
$PN"CD2"6;
"UPI1_RX_DN23"
$PN"CB2"5;
%"TAP"
"1","(-850,3575)","2","standard","I103";
;
CDS_LIB"standard"
BODY_TYPE"PLUMBING"
HDL_TAP"TRUE";
"B \NAC \NWC"4;
"S \NAC"
BN"23"29;
%"TAP"
"1","(-850,3525)","2","standard","I104";
;
CDS_LIB"standard"
BODY_TYPE"PLUMBING"
HDL_TAP"TRUE";
"B \NAC \NWC"4;
"S \NAC"
BN"22"30;
%"TAP"
"1","(-850,3425)","2","standard","I105";
;
CDS_LIB"standard"
BODY_TYPE"PLUMBING"
HDL_TAP"TRUE";
"B \NAC \NWC"4;
"S \NAC"
BN"20"32;
%"TAP"
"1","(-850,3375)","2","standard","I106";
;
CDS_LIB"standard"
BODY_TYPE"PLUMBING"
HDL_TAP"TRUE";
"B \NAC \NWC"4;
"S \NAC"
BN"19"33;
%"TAP"
"1","(-850,3275)","2","standard","I107";
;
CDS_LIB"standard"
BODY_TYPE"PLUMBING"
HDL_TAP"TRUE";
"B \NAC \NWC"4;
"S \NAC"
BN"17"35;
%"TAP"
"1","(-850,3025)","2","standard","I108";
;
CDS_LIB"standard"
BODY_TYPE"PLUMBING"
HDL_TAP"TRUE";
"B \NAC \NWC"4;
"S \NAC"
BN"12"40;
%"TAP"
"1","(-650,2325)","2","standard","I109";
;
CDS_LIB"standard"
BODY_TYPE"PLUMBING"
HDL_TAP"TRUE";
"B \NAC \NWC"3;
"S \NAC"
BN"23"5;
%"TAP"
"1","(-850,1675)","2","standard","I11";
;
CDS_LIB"standard"
BODY_TYPE"PLUMBING"
HDL_TAP"TRUE";
"B \NAC \NWC"4;
"S \NAC"
BN"10"18;
%"TAP"
"1","(-650,2125)","2","standard","I111";
;
CDS_LIB"standard"
BODY_TYPE"PLUMBING"
HDL_TAP"TRUE";
"B \NAC \NWC"3;
"S \NAC"
BN"19"9;
%"TAP"
"1","(-850,2075)","2","standard","I112";
;
CDS_LIB"standard"
BODY_TYPE"PLUMBING"
HDL_TAP"TRUE";
"B \NAC \NWC"4;
"S \NAC"
BN"18"10;
%"TAP"
"1","(2725,2175)","0","standard","I113";
;
CDS_LIB"standard"
BODY_TYPE"PLUMBING"
HDL_TAP"TRUE";
"B \NAC \NWC"1;
"S \NAC"
BN"20"56;
%"TAP"
"1","(2725,2225)","0","standard","I114";
;
CDS_LIB"standard"
BODY_TYPE"PLUMBING"
HDL_TAP"TRUE";
"B \NAC \NWC"1;
"S \NAC"
BN"21"55;
%"TAP"
"1","(2725,2325)","0","standard","I115";
;
CDS_LIB"standard"
BODY_TYPE"PLUMBING"
HDL_TAP"TRUE";
"B \NAC \NWC"1;
"S \NAC"
BN"23"53;
%"TAP"
"1","(2725,1325)","0","standard","I116";
;
CDS_LIB"standard"
BODY_TYPE"PLUMBING"
HDL_TAP"TRUE";
"B \NAC \NWC"1;
"S \NAC"
BN"3"73;
%"TAP"
"1","(2725,1425)","0","standard","I117";
;
CDS_LIB"standard"
BODY_TYPE"PLUMBING"
HDL_TAP"TRUE";
"B \NAC \NWC"1;
"S \NAC"
BN"5"71;
%"TAP"
"1","(2725,1675)","0","standard","I118";
;
CDS_LIB"standard"
BODY_TYPE"PLUMBING"
HDL_TAP"TRUE";
"B \NAC \NWC"1;
"S \NAC"
BN"10"66;
%"TAP"
"1","(2725,1725)","0","standard","I119";
;
CDS_LIB"standard"
BODY_TYPE"PLUMBING"
HDL_TAP"TRUE";
"B \NAC \NWC"1;
"S \NAC"
BN"11"65;
%"TAP"
"1","(-650,1775)","2","standard","I12";
;
CDS_LIB"standard"
BODY_TYPE"PLUMBING"
HDL_TAP"TRUE";
"B \NAC \NWC"3;
"S \NAC"
BN"12"16;
%"TAP"
"1","(2725,1775)","0","standard","I120";
;
CDS_LIB"standard"
BODY_TYPE"PLUMBING"
HDL_TAP"TRUE";
"B \NAC \NWC"1;
"S \NAC"
BN"12"64;
%"TAP"
"1","(2725,1825)","0","standard","I121";
;
CDS_LIB"standard"
BODY_TYPE"PLUMBING"
HDL_TAP"TRUE";
"B \NAC \NWC"1;
"S \NAC"
BN"13"63;
%"TAP"
"1","(2725,1925)","0","standard","I122";
;
CDS_LIB"standard"
BODY_TYPE"PLUMBING"
HDL_TAP"TRUE";
"B \NAC \NWC"1;
"S \NAC"
BN"15"61;
%"TAP"
"1","(2725,1975)","0","standard","I123";
;
CDS_LIB"standard"
BODY_TYPE"PLUMBING"
HDL_TAP"TRUE";
"B \NAC \NWC"1;
"S \NAC"
BN"16"60;
%"TAP"
"1","(2725,2025)","0","standard","I124";
;
CDS_LIB"standard"
BODY_TYPE"PLUMBING"
HDL_TAP"TRUE";
"B \NAC \NWC"1;
"S \NAC"
BN"17"59;
%"TAP"
"1","(2725,2125)","0","standard","I125";
;
CDS_LIB"standard"
BODY_TYPE"PLUMBING"
HDL_TAP"TRUE";
"B \NAC \NWC"1;
"S \NAC"
BN"19"57;
%"TAP"
"1","(2925,2575)","0","standard","I126";
;
CDS_LIB"standard"
BODY_TYPE"PLUMBING"
HDL_TAP"TRUE";
"B \NAC \NWC"2;
"S \NAC"
BN"3"97;
%"TAP"
"1","(2925,2675)","0","standard","I127";
;
CDS_LIB"standard"
BODY_TYPE"PLUMBING"
HDL_TAP"TRUE";
"B \NAC \NWC"2;
"S \NAC"
BN"5"95;
%"TAP"
"1","(2925,2925)","0","standard","I128";
;
CDS_LIB"standard"
BODY_TYPE"PLUMBING"
HDL_TAP"TRUE";
"B \NAC \NWC"2;
"S \NAC"
BN"10"90;
%"TAP"
"1","(2925,2975)","0","standard","I129";
;
CDS_LIB"standard"
BODY_TYPE"PLUMBING"
HDL_TAP"TRUE";
"B \NAC \NWC"2;
"S \NAC"
BN"11"89;
%"TAP"
"1","(-850,1725)","2","standard","I13";
;
CDS_LIB"standard"
BODY_TYPE"PLUMBING"
HDL_TAP"TRUE";
"B \NAC \NWC"4;
"S \NAC"
BN"11"17;
%"TAP"
"1","(2925,3025)","0","standard","I130";
;
CDS_LIB"standard"
BODY_TYPE"PLUMBING"
HDL_TAP"TRUE";
"B \NAC \NWC"2;
"S \NAC"
BN"12"88;
%"TAP"
"1","(2925,3075)","0","standard","I131";
;
CDS_LIB"standard"
BODY_TYPE"PLUMBING"
HDL_TAP"TRUE";
"B \NAC \NWC"2;
"S \NAC"
BN"13"87;
%"TAP"
"1","(2925,3175)","0","standard","I132";
;
CDS_LIB"standard"
BODY_TYPE"PLUMBING"
HDL_TAP"TRUE";
"B \NAC \NWC"2;
"S \NAC"
BN"15"85;
%"TAP"
"1","(2925,3225)","0","standard","I133";
;
CDS_LIB"standard"
BODY_TYPE"PLUMBING"
HDL_TAP"TRUE";
"B \NAC \NWC"2;
"S \NAC"
BN"16"84;
%"TAP"
"1","(2925,3275)","0","standard","I134";
;
CDS_LIB"standard"
BODY_TYPE"PLUMBING"
HDL_TAP"TRUE";
"B \NAC \NWC"2;
"S \NAC"
BN"17"83;
%"TAP"
"1","(2925,3375)","0","standard","I135";
;
CDS_LIB"standard"
BODY_TYPE"PLUMBING"
HDL_TAP"TRUE";
"B \NAC \NWC"2;
"S \NAC"
BN"19"81;
%"TAP"
"1","(2925,3575)","0","standard","I137";
;
CDS_LIB"standard"
BODY_TYPE"PLUMBING"
HDL_TAP"TRUE";
"B \NAC \NWC"2;
"S \NAC"
BN"23"77;
%"TAP"
"1","(2925,3475)","0","standard","I138";
;
CDS_LIB"standard"
BODY_TYPE"PLUMBING"
HDL_TAP"TRUE";
"B \NAC \NWC"2;
"S \NAC"
BN"21"79;
%"TAP"
"1","(2925,3425)","0","standard","I139";
;
CDS_LIB"standard"
BODY_TYPE"PLUMBING"
HDL_TAP"TRUE";
"B \NAC \NWC"2;
"S \NAC"
BN"20"80;
%"TAP"
"1","(-850,1875)","2","standard","I14";
;
CDS_LIB"standard"
BODY_TYPE"PLUMBING"
HDL_TAP"TRUE";
"B \NAC \NWC"4;
"S \NAC"
BN"14"14;
%"TAP"
"1","(2925,3125)","0","standard","I140";
;
CDS_LIB"standard"
BODY_TYPE"PLUMBING"
HDL_TAP"TRUE";
"B \NAC \NWC"2;
"S \NAC"
BN"14"86;
%"TAP"
"1","(2725,1875)","0","standard","I141";
;
CDS_LIB"standard"
BODY_TYPE"PLUMBING"
HDL_TAP"TRUE";
"B \NAC \NWC"1;
"S \NAC"
BN"14"62;
%"TAP"
"1","(2725,2075)","0","standard","I142";
;
CDS_LIB"standard"
BODY_TYPE"PLUMBING"
HDL_TAP"TRUE";
"B \NAC \NWC"1;
"S \NAC"
BN"18"58;
%"TAP"
"1","(2925,3325)","0","standard","I143";
;
CDS_LIB"standard"
BODY_TYPE"PLUMBING"
HDL_TAP"TRUE";
"B \NAC \NWC"2;
"S \NAC"
BN"18"82;
%"TAP"
"1","(-650,1275)","2","standard","I144";
;
CDS_LIB"standard"
BODY_TYPE"PLUMBING"
HDL_TAP"TRUE";
"B \NAC \NWC"3;
"S \NAC"
BN"2"26;
%"TAP"
"1","(-850,2525)","2","standard","I145";
;
CDS_LIB"standard"
BODY_TYPE"PLUMBING"
HDL_TAP"TRUE";
"B \NAC \NWC"4;
"S \NAC"
BN"2"50;
%"TAP"
"1","(-850,1825)","2","standard","I15";
;
CDS_LIB"standard"
BODY_TYPE"PLUMBING"
HDL_TAP"TRUE";
"B \NAC \NWC"4;
"S \NAC"
BN"13"15;
%"TAP"
"1","(-850,1925)","2","standard","I16";
;
CDS_LIB"standard"
BODY_TYPE"PLUMBING"
HDL_TAP"TRUE";
"B \NAC \NWC"4;
"S \NAC"
BN"15"13;
%"TAP"
"1","(-850,1975)","2","standard","I19";
;
CDS_LIB"standard"
BODY_TYPE"PLUMBING"
HDL_TAP"TRUE";
"B \NAC \NWC"4;
"S \NAC"
BN"16"12;
%"TAP"
"1","(-850,1225)","2","standard","I2";
;
CDS_LIB"standard"
BODY_TYPE"PLUMBING"
HDL_TAP"TRUE";
"B \NAC \NWC"4;
"S \NAC"
BN"1"27;
%"TAP"
"1","(-650,2025)","2","standard","I20";
;
CDS_LIB"standard"
BODY_TYPE"PLUMBING"
HDL_TAP"TRUE";
"B \NAC \NWC"3;
"S \NAC"
BN"17"11;
%"TAP"
"1","(-650,2175)","2","standard","I22";
;
CDS_LIB"standard"
BODY_TYPE"PLUMBING"
HDL_TAP"TRUE";
"B \NAC \NWC"3;
"S \NAC"
BN"20"8;
%"TAP"
"1","(-850,2225)","2","standard","I24";
;
CDS_LIB"standard"
BODY_TYPE"PLUMBING"
HDL_TAP"TRUE";
"B \NAC \NWC"4;
"S \NAC"
BN"21"7;
%"TAP"
"1","(-650,2275)","2","standard","I25";
;
CDS_LIB"standard"
BODY_TYPE"PLUMBING"
HDL_TAP"TRUE";
"B \NAC \NWC"3;
"S \NAC"
BN"22"6;
%"TAP"
"1","(-650,2425)","2","standard","I27";
;
CDS_LIB"standard"
BODY_TYPE"PLUMBING"
HDL_TAP"TRUE";
"B \NAC \NWC"3;
"S \NAC"
BN"0"52;
%"TAP"
"1","(-650,2475)","2","standard","I29";
;
CDS_LIB"standard"
BODY_TYPE"PLUMBING"
HDL_TAP"TRUE";
"B \NAC \NWC"3;
"S \NAC"
BN"1"51;
%"TAP"
"1","(-650,2575)","2","standard","I30";
;
CDS_LIB"standard"
BODY_TYPE"PLUMBING"
HDL_TAP"TRUE";
"B \NAC \NWC"3;
"S \NAC"
BN"3"49;
%"TAP"
"1","(-650,2675)","2","standard","I31";
;
CDS_LIB"standard"
BODY_TYPE"PLUMBING"
HDL_TAP"TRUE";
"B \NAC \NWC"3;
"S \NAC"
BN"5"47;
%"TAP"
"1","(-650,2625)","2","standard","I32";
;
CDS_LIB"standard"
BODY_TYPE"PLUMBING"
HDL_TAP"TRUE";
"B \NAC \NWC"3;
"S \NAC"
BN"4"48;
%"TAP"
"1","(-650,2725)","2","standard","I33";
;
CDS_LIB"standard"
BODY_TYPE"PLUMBING"
HDL_TAP"TRUE";
"B \NAC \NWC"3;
"S \NAC"
BN"6"46;
%"TAP"
"1","(-650,2775)","2","standard","I34";
;
CDS_LIB"standard"
BODY_TYPE"PLUMBING"
HDL_TAP"TRUE";
"B \NAC \NWC"3;
"S \NAC"
BN"7"45;
%"TAP"
"1","(-650,2825)","2","standard","I35";
;
CDS_LIB"standard"
BODY_TYPE"PLUMBING"
HDL_TAP"TRUE";
"B \NAC \NWC"3;
"S \NAC"
BN"8"44;
%"TAP"
"1","(-650,2925)","2","standard","I36";
;
CDS_LIB"standard"
BODY_TYPE"PLUMBING"
HDL_TAP"TRUE";
"B \NAC \NWC"3;
"S \NAC"
BN"10"42;
%"TAP"
"1","(-650,2875)","2","standard","I37";
;
CDS_LIB"standard"
BODY_TYPE"PLUMBING"
HDL_TAP"TRUE";
"B \NAC \NWC"3;
"S \NAC"
BN"9"43;
%"TAP"
"1","(-650,2975)","2","standard","I38";
;
CDS_LIB"standard"
BODY_TYPE"PLUMBING"
HDL_TAP"TRUE";
"B \NAC \NWC"3;
"S \NAC"
BN"11"41;
%"TAP"
"1","(-850,1325)","2","standard","I4";
;
CDS_LIB"standard"
BODY_TYPE"PLUMBING"
HDL_TAP"TRUE";
"B \NAC \NWC"4;
"S \NAC"
BN"3"25;
%"TAP"
"1","(-650,3075)","2","standard","I40";
;
CDS_LIB"standard"
BODY_TYPE"PLUMBING"
HDL_TAP"TRUE";
"B \NAC \NWC"3;
"S \NAC"
BN"13"39;
%"TAP"
"1","(-650,3125)","2","standard","I41";
;
CDS_LIB"standard"
BODY_TYPE"PLUMBING"
HDL_TAP"TRUE";
"B \NAC \NWC"3;
"S \NAC"
BN"14"38;
%"TAP"
"1","(-650,3175)","2","standard","I42";
;
CDS_LIB"standard"
BODY_TYPE"PLUMBING"
HDL_TAP"TRUE";
"B \NAC \NWC"3;
"S \NAC"
BN"15"37;
%"TAP"
"1","(-650,3225)","2","standard","I43";
;
CDS_LIB"standard"
BODY_TYPE"PLUMBING"
HDL_TAP"TRUE";
"B \NAC \NWC"3;
"S \NAC"
BN"16"36;
%"TAP"
"1","(-650,3325)","2","standard","I44";
;
CDS_LIB"standard"
BODY_TYPE"PLUMBING"
HDL_TAP"TRUE";
"B \NAC \NWC"3;
"S \NAC"
BN"18"34;
%"TAP"
"1","(-650,3475)","2","standard","I48";
;
CDS_LIB"standard"
BODY_TYPE"PLUMBING"
HDL_TAP"TRUE";
"B \NAC \NWC"3;
"S \NAC"
BN"21"31;
%"TAP"
"1","(-850,1375)","2","standard","I5";
;
CDS_LIB"standard"
BODY_TYPE"PLUMBING"
HDL_TAP"TRUE";
"B \NAC \NWC"4;
"S \NAC"
BN"4"24;
%"TAP"
"1","(2925,1175)","0","standard","I52";
;
CDS_LIB"standard"
BODY_TYPE"PLUMBING"
HDL_TAP"TRUE";
"B \NAC \NWC"2;
"S \NAC"
BN"0"76;
%"TAP"
"1","(2925,1225)","0","standard","I53";
;
CDS_LIB"standard"
BODY_TYPE"PLUMBING"
HDL_TAP"TRUE";
"B \NAC \NWC"2;
"S \NAC"
BN"1"75;
%"TAP"
"1","(2925,1275)","0","standard","I54";
;
CDS_LIB"standard"
BODY_TYPE"PLUMBING"
HDL_TAP"TRUE";
"B \NAC \NWC"2;
"S \NAC"
BN"2"74;
%"TAP"
"1","(2925,1375)","0","standard","I56";
;
CDS_LIB"standard"
BODY_TYPE"PLUMBING"
HDL_TAP"TRUE";
"B \NAC \NWC"2;
"S \NAC"
BN"4"72;
%"TAP"
"1","(2925,1475)","0","standard","I58";
;
CDS_LIB"standard"
BODY_TYPE"PLUMBING"
HDL_TAP"TRUE";
"B \NAC \NWC"2;
"S \NAC"
BN"6"70;
%"TAP"
"1","(2925,1525)","0","standard","I59";
;
CDS_LIB"standard"
BODY_TYPE"PLUMBING"
HDL_TAP"TRUE";
"B \NAC \NWC"2;
"S \NAC"
BN"7"69;
%"TAP"
"1","(-850,1425)","2","standard","I6";
;
CDS_LIB"standard"
BODY_TYPE"PLUMBING"
HDL_TAP"TRUE";
"B \NAC \NWC"4;
"S \NAC"
BN"5"23;
%"TAP"
"1","(2925,1575)","0","standard","I61";
;
CDS_LIB"standard"
BODY_TYPE"PLUMBING"
HDL_TAP"TRUE";
"B \NAC \NWC"2;
"S \NAC"
BN"8"68;
%"TAP"
"1","(2925,1625)","0","standard","I62";
;
CDS_LIB"standard"
BODY_TYPE"PLUMBING"
HDL_TAP"TRUE";
"B \NAC \NWC"2;
"S \NAC"
BN"9"67;
%"TAP"
"1","(-850,1525)","2","standard","I7";
;
CDS_LIB"standard"
BODY_TYPE"PLUMBING"
HDL_TAP"TRUE";
"B \NAC \NWC"4;
"S \NAC"
BN"7"21;
%"TAP"
"1","(2725,2425)","0","standard","I75";
;
CDS_LIB"standard"
BODY_TYPE"PLUMBING"
HDL_TAP"TRUE";
"B \NAC \NWC"1;
"S \NAC"
BN"0"100;
%"TAP"
"1","(2925,2275)","0","standard","I76";
;
CDS_LIB"standard"
BODY_TYPE"PLUMBING"
HDL_TAP"TRUE";
"B \NAC \NWC"2;
"S \NAC"
BN"22"54;
%"TAP"
"1","(2725,2525)","0","standard","I77";
;
CDS_LIB"standard"
BODY_TYPE"PLUMBING"
HDL_TAP"TRUE";
"B \NAC \NWC"1;
"S \NAC"
BN"2"98;
%"TAP"
"1","(2725,2475)","0","standard","I78";
;
CDS_LIB"standard"
BODY_TYPE"PLUMBING"
HDL_TAP"TRUE";
"B \NAC \NWC"1;
"S \NAC"
BN"1"99;
%"TAP"
"1","(-850,1475)","2","standard","I8";
;
CDS_LIB"standard"
BODY_TYPE"PLUMBING"
HDL_TAP"TRUE";
"B \NAC \NWC"4;
"S \NAC"
BN"6"22;
%"TAP"
"1","(2725,2625)","0","standard","I81";
;
CDS_LIB"standard"
BODY_TYPE"PLUMBING"
HDL_TAP"TRUE";
"B \NAC \NWC"1;
"S \NAC"
BN"4"96;
%"TAP"
"1","(2725,2875)","0","standard","I82";
;
CDS_LIB"standard"
BODY_TYPE"PLUMBING"
HDL_TAP"TRUE";
"B \NAC \NWC"1;
"S \NAC"
BN"9"91;
%"TAP"
"1","(2725,2825)","0","standard","I84";
;
CDS_LIB"standard"
BODY_TYPE"PLUMBING"
HDL_TAP"TRUE";
"B \NAC \NWC"1;
"S \NAC"
BN"8"92;
%"TAP"
"1","(2725,2775)","0","standard","I85";
;
CDS_LIB"standard"
BODY_TYPE"PLUMBING"
HDL_TAP"TRUE";
"B \NAC \NWC"1;
"S \NAC"
BN"7"93;
%"TAP"
"1","(2725,2725)","0","standard","I86";
;
CDS_LIB"standard"
BODY_TYPE"PLUMBING"
HDL_TAP"TRUE";
"B \NAC \NWC"1;
"S \NAC"
BN"6"94;
%"TAP"
"1","(-850,1575)","2","standard","I9";
;
CDS_LIB"standard"
BODY_TYPE"PLUMBING"
HDL_TAP"TRUE";
"B \NAC \NWC"4;
"S \NAC"
BN"8"20;
%"TAP"
"1","(2725,3525)","0","standard","I99";
;
CDS_LIB"standard"
BODY_TYPE"PLUMBING"
HDL_TAP"TRUE";
"B \NAC \NWC"1;
"S \NAC"
BN"22"78;
END.
